(kicad_pcb
	(version 20260206)
	(generator "pcbnew")
	(generator_version "10.0")
	(general
		(thickness 1.6)
		(legacy_teardrops no)
	)
	(paper "A4")
	(title_block
		(title "Wiwynn_Tioga_Pass_MB.brd")
		(comment 1 "Tioga Pass / footprint 2254 of 4770 (U5D1), pads 80-192 of 3647")
	)
	(layers
		(0 "F.Cu" signal "TOP")
		(4 "In1.Cu" signal "L2GND")
		(6 "In2.Cu" signal "L3")
		(8 "In3.Cu" signal "L4GND")
		(10 "In4.Cu" signal "L5")
		(12 "In5.Cu" signal "L6GND")
		(14 "In6.Cu" signal "L7VCC")
		(16 "In7.Cu" signal "L8VCC")
		(18 "In8.Cu" signal "L9GND")
		(20 "In9.Cu" signal "L10")
		(22 "In10.Cu" signal "L11GND")
		(24 "In11.Cu" signal "L12")
		(26 "In12.Cu" signal "L13GND")
		(2 "B.Cu" signal "BOTTOM")
		(9 "F.Adhes" user "F.Adhesive")
		(11 "B.Adhes" user "B.Adhesive")
		(13 "F.Paste" user "Package Geometry/Pastemask Top")
		(15 "B.Paste" user "Package Geometry/Pastemask Bottom")
		(5 "F.SilkS" user "Ref Des/Silkscreen Top")
		(7 "B.SilkS" user "Ref Des/Silkscreen Bottom")
		(1 "F.Mask" user "Board Geometry/Soldermask Top")
		(3 "B.Mask" user "Board Geometry/Soldermask Bottom")
		(17 "Dwgs.User" user "User.Drawings")
		(19 "Cmts.User" user "User.Comments")
		(21 "Eco1.User" user "User.Eco1")
		(23 "Eco2.User" user "User.Eco2")
		(25 "Edge.Cuts" user "Board Geometry/Outline")
		(27 "Margin" user)
		(31 "F.CrtYd" user "Package Geometry/Place Bound Top")
		(29 "B.CrtYd" user "Package Geometry/Place Bound Bottom")
		(35 "F.Fab" user "Ref Des/Assembly Top")
		(33 "B.Fab" user "Ref Des/Assembly Bottom")
	)
	(footprint ""
		(layer "F.Cu")
		(at 270.000222 -76.550012 180)
		(property "Reference" "U5D1"
			(at 19.124422 31.601918 0)
			(unlocked yes)
			(layer "F.SilkS")
			(effects
				(font
					(size 0.7874 0.5842)
					(thickness 0.1524)
				)
			)
		)
		(property "Value" ""
			(at 0 0 180)
			(layer "F.Fab")
			(effects
				(font
					(size 1.27 1.27)
				)
			)
		)
		(duplicate_pad_numbers_are_jumpers no)
		(pad "AB41" smd circle
			(at -2.910586 -14.702028)
			(size 0.4318 0.4318)
			(layers "F.Cu" "F.Mask" "F.Paste")
			(net "GND")
		)
		(pad "AB43" smd circle
			(at -1.193546 -14.702028)
			(size 0.4318 0.4318)
			(layers "F.Cu" "F.Mask" "F.Paste")
			(net "A_CPU0_ABC_RCOMP1")
		)
		(pad "AB45" smd circle
			(at 2.052066 -16.502126)
			(size 0.508 0.508)
			(layers "F.Cu" "F.Mask" "F.Paste")
			(net "M_C_C<2>")
		)
		(pad "AB47" smd circle
			(at 3.769106 -16.502126)
			(size 0.4318 0.4318)
			(layers "F.Cu" "F.Mask" "F.Paste")
			(net "M_C_ODT<3>")
		)
		(pad "AB49" smd circle
			(at 5.485892 -16.502126)
			(size 0.4318 0.4318)
			(layers "F.Cu" "F.Mask" "F.Paste")
			(net "M_C_CS_N<1>")
		)
		(pad "AB51" smd circle
			(at 7.202932 -16.502126)
			(size 0.4318 0.4318)
			(layers "F.Cu" "F.Mask" "F.Paste")
			(net "M_C_CS_N<4>")
		)
		(pad "AB53" smd circle
			(at 8.919972 -16.502126)
			(size 0.4318 0.4318)
			(layers "F.Cu" "F.Mask" "F.Paste")
			(net "M_C_MA<0>")
		)
		(pad "AB55" smd circle
			(at 10.637012 -16.502126)
			(size 0.4318 0.4318)
			(layers "F.Cu" "F.Mask" "F.Paste")
			(net "M_C_CLK_DP<0>")
		)
		(pad "AB57" smd circle
			(at 12.354052 -16.502126)
			(size 0.4318 0.4318)
			(layers "F.Cu" "F.Mask" "F.Paste")
			(net "M_C_CLK_DP<2>")
		)
		(pad "AB59" smd circle
			(at 14.071092 -16.502126)
			(size 0.4318 0.4318)
			(layers "F.Cu" "F.Mask" "F.Paste")
			(net "M_C_MA<6>")
		)
		(pad "AB61" smd circle
			(at 15.787878 -16.502126)
			(size 0.4318 0.4318)
			(layers "F.Cu" "F.Mask" "F.Paste")
			(net "M_C_ACT_N")
		)
		(pad "AB63" smd circle
			(at 17.504918 -16.502126)
			(size 0.4318 0.4318)
			(layers "F.Cu" "F.Mask" "F.Paste")
			(net "M_C_CKE<3>")
		)
		(pad "AB65" smd circle
			(at 19.221958 -16.502126)
			(size 0.4318 0.4318)
			(layers "F.Cu" "F.Mask" "F.Paste")
			(net "GND")
		)
		(pad "AB67" smd circle
			(at 20.938998 -16.502126)
			(size 0.4318 0.4318)
			(layers "F.Cu" "F.Mask" "F.Paste")
			(net "M_A_DQS_DN<17>")
		)
		(pad "AB69" smd circle
			(at 22.656038 -16.502126)
			(size 0.4318 0.4318)
			(layers "F.Cu" "F.Mask" "F.Paste")
			(net "GND")
		)
		(pad "AB71" smd circle
			(at 24.373078 -16.502126)
			(size 0.4318 0.4318)
			(layers "F.Cu" "F.Mask" "F.Paste")
			(net "M_C_DQ<21>")
		)
		(pad "AB73" smd circle
			(at 26.090118 -16.502126)
			(size 0.4318 0.4318)
			(layers "F.Cu" "F.Mask" "F.Paste")
			(net "GND")
		)
		(pad "AB75" smd circle
			(at 27.806904 -16.502126)
			(size 0.4318 0.4318)
			(layers "F.Cu" "F.Mask" "F.Paste")
			(net "M_C_DQS_DP<1>")
		)
		(pad "AB77" smd circle
			(at 29.523944 -16.502126)
			(size 0.4318 0.4318)
			(layers "F.Cu" "F.Mask" "F.Paste")
			(net "M_C_DQ<14>")
		)
		(pad "AB79" smd circle
			(at 31.240984 -16.502126)
			(size 0.4318 0.4318)
			(layers "F.Cu" "F.Mask" "F.Paste")
			(net "GND")
		)
		(pad "AB81" smd circle
			(at 32.958024 -16.502126)
			(size 0.4318 0.4318)
			(layers "F.Cu" "F.Mask" "F.Paste")
			(net "M_B_DQ<11>")
		)
		(pad "AB83" smd circle
			(at 34.675064 -16.502126)
			(size 0.4318 0.4318)
			(layers "F.Cu" "F.Mask" "F.Paste")
			(net "GND")
		)
		(pad "AB85" smd circle
			(at 36.392104 -16.502126)
			(size 0.4318 0.4318)
			(layers "F.Cu" "F.Mask" "F.Paste")
			(net "GND")
		)
		(pad "AC2" smd circle
			(at -36.392104 -14.206474)
			(size 0.4318 0.4318)
			(layers "F.Cu" "F.Mask" "F.Paste")
			(net "UPI_CPU0_CPU1_P0P0_DN<14>")
		)
		(pad "AC4" smd circle
			(at -34.675064 -14.206474)
			(size 0.4318 0.4318)
			(layers "F.Cu" "F.Mask" "F.Paste")
			(net "PVCCIO_CPU0")
		)
		(pad "AC6" smd circle
			(at -32.958024 -14.206474)
			(size 0.4318 0.4318)
			(layers "F.Cu" "F.Mask" "F.Paste")
			(net "UPI_CPU1_CPU0_P0P0_DP<16>")
		)
		(pad "AC8" smd circle
			(at -31.240984 -14.206474)
			(size 0.4318 0.4318)
			(layers "F.Cu" "F.Mask" "F.Paste")
			(net "UPI_CPU1_CPU0_P0P0_DP<18>")
		)
		(pad "AC10" smd circle
			(at -29.523944 -14.206474)
			(size 0.4318 0.4318)
			(layers "F.Cu" "F.Mask" "F.Paste")
			(net "UPI_CPU1_CPU0_P0P0_DN<19>")
		)
		(pad "AC12" smd circle
			(at -27.806904 -14.206474)
			(size 0.4318 0.4318)
			(layers "F.Cu" "F.Mask" "F.Paste")
			(net "XDP_CPU_OBSFN_B1_MBP7_N")
		)
		(pad "AC14" smd circle
			(at -26.090118 -14.206474)
			(size 0.4318 0.4318)
			(layers "F.Cu" "F.Mask" "F.Paste")
			(net "XDP_CPU_TDI")
		)
		(pad "AC16" smd circle
			(at -24.373078 -14.206474)
			(size 0.4318 0.4318)
			(layers "F.Cu" "F.Mask" "F.Paste")
			(net "H_CPU0_PROCHOT_G_N")
		)
		(pad "AC18" smd circle
			(at -22.656038 -14.206474)
			(size 0.4318 0.4318)
			(layers "F.Cu" "F.Mask" "F.Paste")
			(net "GND")
		)
		(pad "AC20" smd circle
			(at -20.938998 -14.206474)
			(size 0.4318 0.4318)
			(layers "F.Cu" "F.Mask" "F.Paste")
			(net "PVCCIO_CPU0")
		)
		(pad "AC22" smd circle
			(at -19.221958 -14.206474)
			(size 0.4318 0.4318)
			(layers "F.Cu" "F.Mask" "F.Paste")
			(net "GND")
		)
		(pad "AC24" smd circle
			(at -17.504918 -14.206474)
			(size 0.4318 0.4318)
			(layers "F.Cu" "F.Mask" "F.Paste")
			(net "M_C_DQS_DN<16>")
		)
		(pad "AC26" smd circle
			(at -15.787878 -14.206474)
			(size 0.4318 0.4318)
			(layers "F.Cu" "F.Mask" "F.Paste")
			(net "GND")
		)
		(pad "AC28" smd circle
			(at -14.071092 -14.206474)
			(size 0.4318 0.4318)
			(layers "F.Cu" "F.Mask" "F.Paste")
			(net "GND")
		)
		(pad "AC30" smd circle
			(at -12.354052 -14.206474)
			(size 0.4318 0.4318)
			(layers "F.Cu" "F.Mask" "F.Paste")
			(net "M_C_DQS_DN<15>")
		)
		(pad "AC32" smd circle
			(at -10.637012 -14.206474)
			(size 0.4318 0.4318)
			(layers "F.Cu" "F.Mask" "F.Paste")
			(net "GND")
		)
		(pad "AC34" smd circle
			(at -8.919972 -14.206474)
			(size 0.4318 0.4318)
			(layers "F.Cu" "F.Mask" "F.Paste")
			(net "GND")
		)
		(pad "AC36" smd circle
			(at -7.202932 -14.206474)
			(size 0.4318 0.4318)
			(layers "F.Cu" "F.Mask" "F.Paste")
			(net "PVCCIO_CPU0")
		)
		(pad "AC38" smd circle
			(at -5.485892 -14.206474)
			(size 0.4318 0.4318)
			(layers "F.Cu" "F.Mask" "F.Paste")
			(net "GND")
		)
		(pad "AC40" smd circle
			(at -3.769106 -14.206474)
			(size 0.4318 0.4318)
			(layers "F.Cu" "F.Mask" "F.Paste")
			(net "GND")
		)
		(pad "AC42" smd circle
			(at -2.052066 -14.206474)
			(size 0.4318 0.4318)
			(layers "F.Cu" "F.Mask" "F.Paste")
			(net "A_CPU0_ABC_RCOMP2")
		)
		(pad "AC46" smd circle
			(at 2.910586 -16.006572)
			(size 0.4318 0.4318)
			(layers "F.Cu" "F.Mask" "F.Paste")
			(net "M_C_MA<17>")
		)
		(pad "AC48" smd circle
			(at 4.627626 -16.006572)
			(size 0.4318 0.4318)
			(layers "F.Cu" "F.Mask" "F.Paste")
			(net "GND")
		)
		(pad "AC50" smd circle
			(at 6.344412 -16.006572)
			(size 0.4318 0.4318)
			(layers "F.Cu" "F.Mask" "F.Paste")
			(net "GND")
		)
		(pad "AC52" smd circle
			(at 8.061452 -16.006572)
			(size 0.4318 0.4318)
			(layers "F.Cu" "F.Mask" "F.Paste")
			(net "GND")
		)
		(pad "AC54" smd circle
			(at 9.778492 -16.006572)
			(size 0.4318 0.4318)
			(layers "F.Cu" "F.Mask" "F.Paste")
			(net "GND")
		)
		(pad "AC56" smd circle
			(at 11.495532 -16.006572)
			(size 0.4318 0.4318)
			(layers "F.Cu" "F.Mask" "F.Paste")
			(net "GND")
		)
		(pad "AC58" smd circle
			(at 13.212572 -16.006572)
			(size 0.4318 0.4318)
			(layers "F.Cu" "F.Mask" "F.Paste")
			(net "GND")
		)
		(pad "AC60" smd circle
			(at 14.929612 -16.006572)
			(size 0.4318 0.4318)
			(layers "F.Cu" "F.Mask" "F.Paste")
			(net "GND")
		)
		(pad "AC62" smd circle
			(at 16.646398 -16.006572)
			(size 0.4318 0.4318)
			(layers "F.Cu" "F.Mask" "F.Paste")
			(net "GND")
		)
		(pad "AC64" smd circle
			(at 18.363438 -16.006572)
			(size 0.4318 0.4318)
			(layers "F.Cu" "F.Mask" "F.Paste")
			(net "GND")
		)
		(pad "AC66" smd circle
			(at 20.080478 -16.006572)
			(size 0.4318 0.4318)
			(layers "F.Cu" "F.Mask" "F.Paste")
			(net "M_A_ECC<6>")
		)
		(pad "AC68" smd circle
			(at 21.797518 -16.006572)
			(size 0.4318 0.4318)
			(layers "F.Cu" "F.Mask" "F.Paste")
			(net "M_A_ECC<0>")
		)
		(pad "AC70" smd circle
			(at 23.514558 -16.006572)
			(size 0.4318 0.4318)
			(layers "F.Cu" "F.Mask" "F.Paste")
			(net "GND")
		)
		(pad "AC72" smd circle
			(at 25.231598 -16.006572)
			(size 0.4318 0.4318)
			(layers "F.Cu" "F.Mask" "F.Paste")
			(net "GND")
		)
		(pad "AC74" smd circle
			(at 26.948384 -16.006572)
			(size 0.4318 0.4318)
			(layers "F.Cu" "F.Mask" "F.Paste")
			(net "M_C_DQ<9>")
		)
		(pad "AC76" smd circle
			(at 28.665424 -16.006572)
			(size 0.4318 0.4318)
			(layers "F.Cu" "F.Mask" "F.Paste")
			(net "M_C_DQS_DP<10>")
		)
		(pad "AC78" smd circle
			(at 30.382464 -16.006572)
			(size 0.4318 0.4318)
			(layers "F.Cu" "F.Mask" "F.Paste")
			(net "GND")
		)
		(pad "AC80" smd circle
			(at 32.099504 -16.006572)
			(size 0.4318 0.4318)
			(layers "F.Cu" "F.Mask" "F.Paste")
			(net "M_B_DQ<15>")
		)
		(pad "AC82" smd circle
			(at 33.816544 -16.006572)
			(size 0.4318 0.4318)
			(layers "F.Cu" "F.Mask" "F.Paste")
			(net "M_B_DQ<10>")
		)
		(pad "AC84" smd circle
			(at 35.533584 -16.006572)
			(size 0.4318 0.4318)
			(layers "F.Cu" "F.Mask" "F.Paste")
			(net "GND")
		)
		(pad "AC86" smd custom
			(at 37.250624 -16.006572 270)
			(size 0.10795 0.10795)
			(layers "F.Cu" "F.Mask" "F.Paste")
			(net "GND")
			(options
				(clearance outline)
				(anchor circle)
			)
			(primitives
				(gr_poly
					(pts
						(arc
							(start 0.2159 -0.0381)
							(mid 0 -0.254)
							(end -0.2159 -0.0381)
						)
						(arc
							(start -0.2159 0.0381)
							(mid 0 0.254)
							(end 0.2159 0.0381)
						)
					)
					(width 0)
					(fill yes)
				)
			)
		)
		(pad "AD1" smd custom
			(at -37.250624 -13.711428 90)
			(size 0.10795 0.10795)
			(layers "F.Cu" "F.Mask" "F.Paste")
			(net "UPI_CPU0_CPU1_P0P0_DP<14>")
			(options
				(clearance outline)
				(anchor circle)
			)
			(primitives
				(gr_poly
					(pts
						(arc
							(start 0.2159 -0.0381)
							(mid 0 -0.254)
							(end -0.2159 -0.0381)
						)
						(arc
							(start -0.2159 0.0381)
							(mid 0 0.254)
							(end 0.2159 0.0381)
						)
					)
					(width 0)
					(fill yes)
				)
			)
		)
		(pad "AD3" smd circle
			(at -35.533584 -13.711428)
			(size 0.4318 0.4318)
			(layers "F.Cu" "F.Mask" "F.Paste")
			(net "GND")
		)
		(pad "AD5" smd circle
			(at -33.816544 -13.711428)
			(size 0.4318 0.4318)
			(layers "F.Cu" "F.Mask" "F.Paste")
			(net "UPI_CPU1_CPU0_P0P0_DN<16>")
		)
		(pad "AD7" smd circle
			(at -32.099504 -13.711428)
			(size 0.4318 0.4318)
			(layers "F.Cu" "F.Mask" "F.Paste")
			(net "GND")
		)
		(pad "AD9" smd circle
			(at -30.382464 -13.711428)
			(size 0.4318 0.4318)
			(layers "F.Cu" "F.Mask" "F.Paste")
			(net "GND")
		)
		(pad "AD11" smd circle
			(at -28.665424 -13.711428)
			(size 0.4318 0.4318)
			(layers "F.Cu" "F.Mask" "F.Paste")
			(net "GND")
		)
		(pad "AD13" smd circle
			(at -26.948384 -13.711428)
			(size 0.4318 0.4318)
			(layers "F.Cu" "F.Mask" "F.Paste")
			(net "GND")
		)
		(pad "AD15" smd circle
			(at -25.231598 -13.711428)
			(size 0.4318 0.4318)
			(layers "F.Cu" "F.Mask" "F.Paste")
			(net "GND")
		)
		(pad "AD17" smd circle
			(at -23.514558 -13.711428)
			(size 0.4318 0.4318)
			(layers "F.Cu" "F.Mask" "F.Paste")
			(net "SMB_DDR_DEF_SDA_G_R")
		)
		(pad "AD19" smd circle
			(at -21.797518 -13.711428)
			(size 0.4318 0.4318)
			(layers "F.Cu" "F.Mask" "F.Paste")
			(net "GND")
		)
		(pad "AD21" smd circle
			(at -20.080478 -13.711428)
			(size 0.4318 0.4318)
			(layers "F.Cu" "F.Mask" "F.Paste")
			(net "GND")
		)
		(pad "AD23" smd circle
			(at -18.363438 -13.711428)
			(size 0.4318 0.4318)
			(layers "F.Cu" "F.Mask" "F.Paste")
			(net "M_C_DQ<62>")
		)
		(pad "AD25" smd circle
			(at -16.646398 -13.711428)
			(size 0.4318 0.4318)
			(layers "F.Cu" "F.Mask" "F.Paste")
			(net "M_C_DQ<56>")
		)
		(pad "AD27" smd circle
			(at -14.929612 -13.711428)
			(size 0.4318 0.4318)
			(layers "F.Cu" "F.Mask" "F.Paste")
			(net "GND")
		)
		(pad "AD29" smd circle
			(at -13.212572 -13.711428)
			(size 0.4318 0.4318)
			(layers "F.Cu" "F.Mask" "F.Paste")
			(net "M_C_DQ<54>")
		)
		(pad "AD31" smd circle
			(at -11.495532 -13.711428)
			(size 0.4318 0.4318)
			(layers "F.Cu" "F.Mask" "F.Paste")
			(net "M_C_DQ<48>")
		)
		(pad "AD33" smd circle
			(at -9.778492 -13.711428)
			(size 0.4318 0.4318)
			(layers "F.Cu" "F.Mask" "F.Paste")
			(net "GND")
		)
		(pad "AD35" smd circle
			(at -8.061452 -13.711428)
			(size 0.4318 0.4318)
			(layers "F.Cu" "F.Mask" "F.Paste")
			(net "PVCCIO_CPU0")
		)
		(pad "AD37" smd circle
			(at -6.344412 -13.711428)
			(size 0.4318 0.4318)
			(layers "F.Cu" "F.Mask" "F.Paste")
			(net "PVCCIO_CPU0")
		)
		(pad "AD39" smd circle
			(at -4.627626 -13.711428)
			(size 0.4318 0.4318)
			(layers "F.Cu" "F.Mask" "F.Paste")
			(net "GND")
		)
		(pad "AD41" smd circle
			(at -2.910586 -13.711428)
			(size 0.4318 0.4318)
			(layers "F.Cu" "F.Mask" "F.Paste")
			(net "VSENSE_PMAX_CPU0")
		)
		(pad "AD43" smd circle
			(at -1.193546 -13.711428)
			(size 0.4318 0.4318)
			(layers "F.Cu" "F.Mask" "F.Paste")
			(net "GND")
		)
		(pad "AD45" smd circle
			(at 2.052066 -15.511526)
			(size 0.508 0.508)
			(layers "F.Cu" "F.Mask" "F.Paste")
			(net "PVDDQ_ABC")
		)
		(pad "AD47" smd circle
			(at 3.769106 -15.511526)
			(size 0.4318 0.4318)
			(layers "F.Cu" "F.Mask" "F.Paste")
			(net "TP_CPU0_RSVD_254")
		)
		(pad "AD49" smd circle
			(at 5.485892 -15.511526)
			(size 0.4318 0.4318)
			(layers "F.Cu" "F.Mask" "F.Paste")
			(net "TP_CPU0_RSVD_253")
		)
		(pad "AD51" smd circle
			(at 7.202932 -15.511526)
			(size 0.4318 0.4318)
			(layers "F.Cu" "F.Mask" "F.Paste")
			(net "TP_CPU0_RSVD_252")
		)
		(pad "AD53" smd circle
			(at 8.919972 -15.511526)
			(size 0.4318 0.4318)
			(layers "F.Cu" "F.Mask" "F.Paste")
			(net "M_C_MA<13>")
		)
		(pad "AD55" smd circle
			(at 10.637012 -15.511526)
			(size 0.4318 0.4318)
			(layers "F.Cu" "F.Mask" "F.Paste")
			(net "M_C_MA<10>")
		)
		(pad "AD57" smd circle
			(at 12.354052 -15.511526)
			(size 0.4318 0.4318)
			(layers "F.Cu" "F.Mask" "F.Paste")
			(net "M_C_MA<2>")
		)
		(pad "AD59" smd circle
			(at 14.071092 -15.511526)
			(size 0.4318 0.4318)
			(layers "F.Cu" "F.Mask" "F.Paste")
			(net "M_C_MA<8>")
		)
		(pad "AD61" smd circle
			(at 15.787878 -15.511526)
			(size 0.4318 0.4318)
			(layers "F.Cu" "F.Mask" "F.Paste")
			(net "M_C_ALERT_N")
		)
		(pad "AD63" smd circle
			(at 17.504918 -15.511526)
			(size 0.4318 0.4318)
			(layers "F.Cu" "F.Mask" "F.Paste")
			(net "M_C_CKE<1>")
		)
		(pad "AD65" smd circle
			(at 19.221958 -15.511526)
			(size 0.4318 0.4318)
			(layers "F.Cu" "F.Mask" "F.Paste")
			(net "M_A_ECC<2>")
		)
		(pad "AD67" smd circle
			(at 20.938998 -15.511526)
			(size 0.4318 0.4318)
			(layers "F.Cu" "F.Mask" "F.Paste")
			(net "M_A_DQS_DP<17>")
		)
		(pad "AD69" smd circle
			(at 22.656038 -15.511526)
			(size 0.4318 0.4318)
			(layers "F.Cu" "F.Mask" "F.Paste")
			(net "M_A_ECC<4>")
		)
		(pad "AD71" smd circle
			(at 24.373078 -15.511526)
			(size 0.4318 0.4318)
			(layers "F.Cu" "F.Mask" "F.Paste")
			(net "GND")
		)
		(pad "AD73" smd circle
			(at 26.090118 -15.511526)
			(size 0.4318 0.4318)
			(layers "F.Cu" "F.Mask" "F.Paste")
			(net "GND")
		)
		(pad "AD75" smd circle
			(at 27.806904 -15.511526)
			(size 0.4318 0.4318)
			(layers "F.Cu" "F.Mask" "F.Paste")
			(net "GND")
		)
		(pad "AD77" smd circle
			(at 29.523944 -15.511526)
			(size 0.4318 0.4318)
			(layers "F.Cu" "F.Mask" "F.Paste")
			(net "M_C_DQS_DN<10>")
		)
		(pad "AD79" smd circle
			(at 31.240984 -15.511526)
			(size 0.4318 0.4318)
			(layers "F.Cu" "F.Mask" "F.Paste")
			(net "M_B_DQS_DN<1>")
		)
		(pad "AD81" smd circle
			(at 32.958024 -15.511526)
			(size 0.4318 0.4318)
			(layers "F.Cu" "F.Mask" "F.Paste")
			(net "GND")
		)
		(pad "AD83" smd circle
			(at 34.675064 -15.511526)
			(size 0.4318 0.4318)
			(layers "F.Cu" "F.Mask" "F.Paste")
			(net "GND")
		)
		(pad "AD85" smd circle
			(at 36.392104 -15.511526)
			(size 0.4318 0.4318)
			(layers "F.Cu" "F.Mask" "F.Paste")
			(net "GND")
		)
		(pad "AE2" smd circle
			(at -36.392104 -13.215874)
			(size 0.4318 0.4318)
			(layers "F.Cu" "F.Mask" "F.Paste")
			(net "UPI_CPU0_CPU1_P0P0_DN<12>")
		)
		(pad "AE4" smd circle
			(at -34.675064 -13.215874)
			(size 0.4318 0.4318)
			(layers "F.Cu" "F.Mask" "F.Paste")
			(net "GND")
		)
		(pad "AE6" smd circle
			(at -32.958024 -13.215874)
			(size 0.4318 0.4318)
			(layers "F.Cu" "F.Mask" "F.Paste")
			(net "UPI_CPU1_CPU0_P0P0_DN<15>")
		)
		(pad "AE8" smd circle
			(at -31.240984 -13.215874)
			(size 0.4318 0.4318)
			(layers "F.Cu" "F.Mask" "F.Paste")
			(net "GND")
		)
		(pad "AE10" smd circle
			(at -29.523944 -13.215874)
			(size 0.4318 0.4318)
			(layers "F.Cu" "F.Mask" "F.Paste")
			(net "PVCCIO_CPU0")
		)
	)
)
